# BASEBOARD_FAB2 (Tioga Pass) — schematic netlist excerpt (pin names and nets, part order shuffled) for the footprints in the layout excerpt that follows; sources: Cadence DE-HDL packaged netlist, KiCad conversion of Wiwynn_Tioga_Pass_MB.brd

J8G1  SCONN200_H68296001  CONN  pkg SM  page 108
  IO1  = P12V
  IO2  = P12V
  IO3  = P12V
  IO4  = P12V
  IO5  = P12V
  IO6  = P12V
  IO7  = P12V
  IO8  = P12V
  IO9  = P12V
  IO10  = P12V
  IO11  = P12V
  IO12  = P12V
  IO13  = GND
  IO14  = GND
  IO15  = SMB_SLOTX24_STBY_LVC3_SDA_R2
  IO16  = IRQ_OOB_MGMT_RISER_ALERT_N
  IO17  = SMB_SLOTX24_STBY_LVC3_SCL_R2
  IO18  = FM_SLT_CFG1
  IO19  = FM_SLT_CFG0
  IO20  = FM_PWRBRK_SLOT_N
  IO21  = P3V3
  IO22  = P3V3
  IO23  = P3V3
  IO24  = P3V3
  IO25  = P3V3_STBY
  IO26  = GND
  IO27  = PU_PCH_TLS_ENABLE_STRAP
  IO28  = FM_PE_SLOTX24_WAKE_N
  IO29  = RST_PCIE_RISER1_PERST_R_N
  IO30  = SMB_HOST_STBY_LVC3_SDA_R5
  IO31  = GND
  IO32  = SMB_HOST_STBY_LVC3_SCL_R5
  IO33  = CLK_100M_PCH_SLOTX24_S5_DP
  IO34  = GND
  IO35  = CLK_100M_PCH_SLOTX24_S5_DN
  IO36  = CLK_100M_PCH_SLOTX24_S4_DP
  IO37  = GND
  IO38  = CLK_100M_PCH_SLOTX24_S4_DN
  IO39  = CLK_100M_PCH_SLOTX24_S0_DP
  IO40  = GND
  IO41  = CLK_100M_PCH_SLOTX24_S0_DN
  IO42  = CLK_100M_PCH_SLOTX24_S1_DP
  IO43  = GND
  IO44  = CLK_100M_PCH_SLOTX24_S1_DN
  IO45  = CLK_100M_PCH_SLOTX24_S3_DP
  IO46  = GND
  IO47  = CLK_100M_PCH_SLOTX24_S3_DN
  IO48  = CLK_100M_PCH_SLOTX24_S2_DP
  IO49  = GND
  IO50  = CLK_100M_PCH_SLOTX24_S2_DN
  IO51  = P3E_CPU0_PE1_PCH_CON_TXN<15>
  IO52  = GND
  IO53  = P3E_CPU0_PE1_PCH_CON_TXP<15>
  IO54  = P3E_CPU0_PE1_PCH_CON_RXN<15>
  IO55  = GND
  IO56  = P3E_CPU0_PE1_PCH_CON_RXP<15>
  IO57  = P3E_CPU0_PE1_PCH_CON_TXP<14>
  IO58  = GND
  IO59  = P3E_CPU0_PE1_PCH_CON_TXN<14>
  IO60  = P3E_CPU0_PE1_PCH_CON_RXN<14>
  IO61  = GND
  IO62  = P3E_CPU0_PE1_PCH_CON_RXP<14>
  IO63  = TP_SLOTX24_RSVD63
  IO64  = GND
  IO65  = GND
  IO66  = TP_SLOTX24_RSVD66
  IO67  = P3E_CPU0_PE1_PCH_CON_TXN<13>
  IO68  = GND
  IO69  = P3E_CPU0_PE1_PCH_CON_TXP<13>
  IO70  = P3E_CPU0_PE1_PCH_CON_RXN<13>
  IO71  = GND
  IO72  = P3E_CPU0_PE1_PCH_CON_RXP<13>
  IO73  = P3E_CPU0_PE1_PCH_CON_TXN<12>
  IO74  = GND
  IO75  = P3E_CPU0_PE1_PCH_CON_TXP<12>
  IO76  = P3E_CPU0_PE1_PCH_CON_RXN<12>
  IO77  = GND
  IO78  = P3E_CPU0_PE1_PCH_CON_RXP<12>
  IO79  = P3E_CPU0_PE1_PCH_CON_TXN<11>
  IO80  = GND
  IO81  = P3E_CPU0_PE1_PCH_CON_TXP<11>
  IO82  = P3E_CPU0_PE1_PCH_CON_RXN<11>
  IO83  = GND
  IO84  = P3E_CPU0_PE1_PCH_CON_RXP<11>
  IO85  = P3E_CPU0_PE1_PCH_CON_TXN<10>
  IO86  = GND
  IO87  = P3E_CPU0_PE1_PCH_CON_TXP<10>
  IO88  = P3E_CPU0_PE1_PCH_CON_RXN<10>
  IO89  = GND
  IO90  = P3E_CPU0_PE1_PCH_CON_RXP<10>
  IO91  = P3E_CPU0_PE1_PCH_CON_TXN<9>
  IO92  = GND
  IO93  = P3E_CPU0_PE1_PCH_CON_TXP<9>
  IO94  = P3E_CPU0_PE1_PCH_CON_RXN<9>
  IO95  = GND
  IO96  = P3E_CPU0_PE1_PCH_CON_RXP<9>
  IO97  = P3E_CPU0_PE1_PCH_CON_TXN<8>
  IO98  = GND
  IO99  = P3E_CPU0_PE1_PCH_CON_TXP<8>
  IO100  = P3E_CPU0_PE1_PCH_CON_RXN<8>
  IO101  = GND
  IO102  = P3E_CPU0_PE1_PCH_CON_RXP<8>
  IO103  = P3E_CPU0_PE1_SS_C_TXP<7>
  IO104  = GND
  IO105  = P3E_CPU0_PE1_SS_C_TXN<7>
  IO106  = P3E_CPU0_PE1_SS_R_RXN<7>
  IO107  = GND
  IO108  = P3E_CPU0_PE1_SS_R_RXP<7>
  IO109  = P3E_CPU0_PE1_SS_C_TXN<6>
  IO110  = GND
  IO111  = P3E_CPU0_PE1_SS_C_TXP<6>
  IO112  = P3E_CPU0_PE1_SS_R_RXN<6>
  IO113  = GND
  IO114  = P3E_CPU0_PE1_SS_R_RXP<6>
  IO115  = P3E_CPU0_PE1_SS_C_TXN<5>
  IO116  = GND
  IO117  = P3E_CPU0_PE1_SS_C_TXP<5>
  IO118  = P3E_CPU0_PE1_SS_R_RXN<5>
  IO119  = GND
  IO120  = P3E_CPU0_PE1_SS_R_RXP<5>
  IO121  = P3E_CPU0_PE1_SS_C_TXN<4>
  IO122  = GND
  IO123  = P3E_CPU0_PE1_SS_C_TXP<4>
  IO124  = P3E_CPU0_PE1_SS_R_RXN<4>
  IO125  = GND
  IO126  = P3E_CPU0_PE1_SS_R_RXP<4>
  IO127  = P3E_CPU0_PE1_SS_C_TXN<3>
  IO128  = GND
  IO129  = P3E_CPU0_PE1_SS_C_TXP<3>
  IO130  = P3E_CPU0_PE1_SS_R_RXN<3>
  IO131  = GND
  IO132  = P3E_CPU0_PE1_SS_R_RXP<3>
  IO133  = P3E_CPU0_PE1_SS_C_TXN<2>
  IO134  = GND
  IO135  = P3E_CPU0_PE1_SS_C_TXP<2>
  IO136  = P3E_CPU0_PE1_SS_R_RXN<2>
  IO137  = GND
  IO138  = P3E_CPU0_PE1_SS_R_RXP<2>
  IO139  = P3E_CPU0_PE1_SS_C_TXN<1>
  IO140  = GND
  IO141  = P3E_CPU0_PE1_SS_C_TXP<1>
  IO142  = P3E_CPU0_PE1_SS_R_RXN<1>
  IO143  = GND
  IO144  = P3E_CPU0_PE1_SS_R_RXP<1>
  IO145  = P3E_CPU0_PE1_SS_C_TXN<0>
  IO146  = GND
  IO147  = P3E_CPU0_PE1_SS_C_TXP<0>
  IO148  = P3E_CPU0_PE1_SS_R_RXN<0>
  IO149  = GND
  IO150  = P3E_CPU0_PE1_SS_R_RXP<0>
  IO151  = P3E_CPU0_PE2_SS_C_TXN<0>
  IO152  = GND
  IO153  = P3E_CPU0_PE2_SS_C_TXP<0>
  IO154  = P3E_CPU0_PE2_SS_RXN<0>
  IO155  = GND
  IO156  = P3E_CPU0_PE2_SS_RXP<0>
  IO157  = P3E_CPU0_PE2_SS_C_TXP<1>
  IO158  = GND
  IO159  = P3E_CPU0_PE2_SS_C_TXN<1>
  IO160  = P3E_CPU0_PE2_SS_RXN<1>
  IO161  = GND
  IO162  = P3E_CPU0_PE2_SS_RXP<1>
  IO163  = P3E_CPU0_PE2_SS_C_TXN<2>
  IO164  = GND
  IO165  = P3E_CPU0_PE2_SS_C_TXP<2>
  IO166  = P3E_CPU0_PE2_SS_RXN<2>
  IO167  = GND
  IO168  = P3E_CPU0_PE2_SS_RXP<2>
  IO169  = P3E_CPU0_PE2_SS_C_TXN<3>
  IO170  = GND
  IO171  = P3E_CPU0_PE2_SS_C_TXP<3>
  IO172  = P3E_CPU0_PE2_SS_RXN<3>
  IO173  = GND
  IO174  = P3E_CPU0_PE2_SS_RXP<3>
  IO175  = P3E_CPU0_PE2_SS_C_TXN<4>
  IO176  = GND
  IO177  = P3E_CPU0_PE2_SS_C_TXP<4>
  IO178  = P3E_CPU0_PE2_SS_RXN<4>
  IO179  = GND
  IO180  = P3E_CPU0_PE2_SS_RXP<4>
  IO181  = P3E_CPU0_PE2_SS_C_TXN<5>
  IO182  = GND
  IO183  = P3E_CPU0_PE2_SS_C_TXP<5>
  IO184  = P3E_CPU0_PE2_SS_RXN<5>
  IO185  = GND
  IO186  = P3E_CPU0_PE2_SS_RXP<5>
  IO187  = P3E_CPU0_PE2_SS_C_TXN<6>
  IO188  = GND
  IO189  = P3E_CPU0_PE2_SS_C_TXP<6>
  IO190  = P3E_CPU0_PE2_SS_RXP<6>
  IO191  = GND
  IO192  = P3E_CPU0_PE2_SS_RXN<6>
  IO193  = P3E_CPU0_PE2_SS_C_TXN<7>
  IO194  = GND
  IO195  = P3E_CPU0_PE2_SS_C_TXP<7>
  IO196  = P3E_CPU0_PE2_SS_RXN<7>
  IO197  = GND
  IO198  = P3E_CPU0_PE2_SS_RXP<7>
  IO199  = FM_PRSNT_2_6_N
  IO200  = GND
  MH1  = GND
  MH2  = GND

(kicad_pcb
	(version 20260206)
	(generator "pcbnew")
	(generator_version "10.0")
	(general
		(thickness 1.6)
		(legacy_teardrops no)
	)
	(paper "A4")
	(title_block
		(title "Wiwynn_Tioga_Pass_MB.brd")
		(comment 1 "Tioga Pass / footprint 949 of 4770 (J8G1), pads 49-93 of 204")
	)
	(layers
		(0 "F.Cu" signal "TOP")
		(4 "In1.Cu" signal "L2GND")
		(6 "In2.Cu" signal "L3")
		(8 "In3.Cu" signal "L4GND")
		(10 "In4.Cu" signal "L5")
		(12 "In5.Cu" signal "L6GND")
		(14 "In6.Cu" signal "L7VCC")
		(16 "In7.Cu" signal "L8VCC")
		(18 "In8.Cu" signal "L9GND")
		(20 "In9.Cu" signal "L10")
		(22 "In10.Cu" signal "L11GND")
		(24 "In11.Cu" signal "L12")
		(26 "In12.Cu" signal "L13GND")
		(2 "B.Cu" signal "BOTTOM")
		(9 "F.Adhes" user "F.Adhesive")
		(11 "B.Adhes" user "B.Adhesive")
		(13 "F.Paste" user "Package Geometry/Pastemask Top")
		(15 "B.Paste" user "Package Geometry/Pastemask Bottom")
		(5 "F.SilkS" user "Ref Des/Silkscreen Top")
		(7 "B.SilkS" user "Ref Des/Silkscreen Bottom")
		(1 "F.Mask" user "Board Geometry/Soldermask Top")
		(3 "B.Mask" user "Board Geometry/Soldermask Bottom")
		(17 "Dwgs.User" user "User.Drawings")
		(19 "Cmts.User" user "User.Comments")
		(21 "Eco1.User" user "User.Eco1")
		(23 "Eco2.User" user "User.Eco2")
		(25 "Edge.Cuts" user "Board Geometry/Outline")
		(27 "Margin" user)
		(31 "F.CrtYd" user "Package Geometry/Place Bound Top")
		(29 "B.CrtYd" user "Package Geometry/Place Bound Bottom")
		(35 "F.Fab" user "Ref Des/Assembly Top")
		(33 "B.Fab" user "Ref Des/Assembly Bottom")
	)
	(footprint ""
		(layer "F.Cu")
		(at 474.080078 -7.789672 -90)
		(property "Reference" "J8G1"
			(at -3.126486 25.39111 0)
			(unlocked yes)
			(layer "F.SilkS")
			(effects
				(font
					(size 0.7874 0.5842)
					(thickness 0.1524)
				)
				(justify left)
			)
		)
		(property "Value" ""
			(at 0 0 270)
			(layer "F.Fab")
			(effects
				(font
					(size 1.27 1.27)
				)
			)
		)
		(duplicate_pad_numbers_are_jumpers no)
		(pad "47" smd rect
			(at 0 18.4023 270)
			(size 1.1938 0.508)
			(layers "F.Cu" "F.Mask" "F.Paste")
			(net "CLK_100M_PCH_SLOTX24_S3_DN")
		)
		(pad "48" smd rect
			(at 3.4036 18.4023 270)
			(size 1.1938 0.508)
			(layers "F.Cu" "F.Mask" "F.Paste")
			(net "CLK_100M_PCH_SLOTX24_S2_DP")
		)
		(pad "49" smd rect
			(at 0 19.2024 270)
			(size 1.1938 0.508)
			(layers "F.Cu" "F.Mask" "F.Paste")
			(net "GND")
		)
		(pad "50" smd rect
			(at 3.4036 19.2024 270)
			(size 1.1938 0.508)
			(layers "F.Cu" "F.Mask" "F.Paste")
			(net "CLK_100M_PCH_SLOTX24_S2_DN")
		)
		(pad "51" smd rect
			(at 0 20.0025 270)
			(size 1.1938 0.508)
			(layers "F.Cu" "F.Mask" "F.Paste")
			(net "P3E_CPU0_PE1_PCH_CON_TXN<15>")
		)
		(pad "52" smd rect
			(at 3.4036 20.0025 270)
			(size 1.1938 0.508)
			(layers "F.Cu" "F.Mask" "F.Paste")
			(net "GND")
		)
		(pad "53" smd rect
			(at 0 20.8026 270)
			(size 1.1938 0.508)
			(layers "F.Cu" "F.Mask" "F.Paste")
			(net "P3E_CPU0_PE1_PCH_CON_TXP<15>")
		)
		(pad "54" smd rect
			(at 3.4036 20.8026 270)
			(size 1.1938 0.508)
			(layers "F.Cu" "F.Mask" "F.Paste")
			(net "P3E_CPU0_PE1_PCH_CON_RXN<15>")
		)
		(pad "55" smd rect
			(at 0 21.6027 270)
			(size 1.1938 0.508)
			(layers "F.Cu" "F.Mask" "F.Paste")
			(net "GND")
		)
		(pad "56" smd rect
			(at 3.4036 21.6027 270)
			(size 1.1938 0.508)
			(layers "F.Cu" "F.Mask" "F.Paste")
			(net "P3E_CPU0_PE1_PCH_CON_RXP<15>")
		)
		(pad "57" smd rect
			(at 0 22.4028 270)
			(size 1.1938 0.508)
			(layers "F.Cu" "F.Mask" "F.Paste")
			(net "P3E_CPU0_PE1_PCH_CON_TXP<14>")
		)
		(pad "58" smd rect
			(at 3.4036 22.4028 270)
			(size 1.1938 0.508)
			(layers "F.Cu" "F.Mask" "F.Paste")
			(net "GND")
		)
		(pad "59" smd rect
			(at 0 23.2029 270)
			(size 1.1938 0.508)
			(layers "F.Cu" "F.Mask" "F.Paste")
			(net "P3E_CPU0_PE1_PCH_CON_TXN<14>")
		)
		(pad "60" smd rect
			(at 3.4036 23.2029 270)
			(size 1.1938 0.508)
			(layers "F.Cu" "F.Mask" "F.Paste")
			(net "P3E_CPU0_PE1_PCH_CON_RXN<14>")
		)
		(pad "61" smd rect
			(at 0 24.003 270)
			(size 1.1938 0.508)
			(layers "F.Cu" "F.Mask" "F.Paste")
			(net "GND")
		)
		(pad "62" smd rect
			(at 3.4036 24.003 270)
			(size 1.1938 0.508)
			(layers "F.Cu" "F.Mask" "F.Paste")
			(net "P3E_CPU0_PE1_PCH_CON_RXP<14>")
		)
		(pad "63" smd rect
			(at 0 24.8031 270)
			(size 1.1938 0.508)
			(layers "F.Cu" "F.Mask" "F.Paste")
			(net "TP_SLOTX24_RSVD63")
		)
		(pad "64" smd rect
			(at 3.4036 24.8031 270)
			(size 1.1938 0.508)
			(layers "F.Cu" "F.Mask" "F.Paste")
			(net "GND")
		)
		(pad "65" smd rect
			(at 0 28.803092 270)
			(size 1.1938 0.508)
			(layers "F.Cu" "F.Mask" "F.Paste")
			(net "GND")
		)
		(pad "66" smd rect
			(at 3.4036 28.803092 270)
			(size 1.1938 0.508)
			(layers "F.Cu" "F.Mask" "F.Paste")
			(net "TP_SLOTX24_RSVD66")
		)
		(pad "67" smd rect
			(at 0 29.603192 270)
			(size 1.1938 0.508)
			(layers "F.Cu" "F.Mask" "F.Paste")
			(net "P3E_CPU0_PE1_PCH_CON_TXN<13>")
		)
		(pad "68" smd rect
			(at 3.4036 29.603192 270)
			(size 1.1938 0.508)
			(layers "F.Cu" "F.Mask" "F.Paste")
			(net "GND")
		)
		(pad "69" smd rect
			(at 0 30.403292 270)
			(size 1.1938 0.508)
			(layers "F.Cu" "F.Mask" "F.Paste")
			(net "P3E_CPU0_PE1_PCH_CON_TXP<13>")
		)
		(pad "70" smd rect
			(at 3.4036 30.403292 270)
			(size 1.1938 0.508)
			(layers "F.Cu" "F.Mask" "F.Paste")
			(net "P3E_CPU0_PE1_PCH_CON_RXN<13>")
		)
		(pad "71" smd rect
			(at 0 31.203392 270)
			(size 1.1938 0.508)
			(layers "F.Cu" "F.Mask" "F.Paste")
			(net "GND")
		)
		(pad "72" smd rect
			(at 3.4036 31.203392 270)
			(size 1.1938 0.508)
			(layers "F.Cu" "F.Mask" "F.Paste")
			(net "P3E_CPU0_PE1_PCH_CON_RXP<13>")
		)
		(pad "73" smd rect
			(at 0 32.003492 270)
			(size 1.1938 0.508)
			(layers "F.Cu" "F.Mask" "F.Paste")
			(net "P3E_CPU0_PE1_PCH_CON_TXN<12>")
		)
		(pad "74" smd rect
			(at 3.4036 32.003492 270)
			(size 1.1938 0.508)
			(layers "F.Cu" "F.Mask" "F.Paste")
			(net "GND")
		)
		(pad "75" smd rect
			(at 0 32.803592 270)
			(size 1.1938 0.508)
			(layers "F.Cu" "F.Mask" "F.Paste")
			(net "P3E_CPU0_PE1_PCH_CON_TXP<12>")
		)
		(pad "76" smd rect
			(at 3.4036 32.803592 270)
			(size 1.1938 0.508)
			(layers "F.Cu" "F.Mask" "F.Paste")
			(net "P3E_CPU0_PE1_PCH_CON_RXN<12>")
		)
		(pad "77" smd rect
			(at 0 33.603692 270)
			(size 1.1938 0.508)
			(layers "F.Cu" "F.Mask" "F.Paste")
			(net "GND")
		)
		(pad "78" smd rect
			(at 3.4036 33.603692 270)
			(size 1.1938 0.508)
			(layers "F.Cu" "F.Mask" "F.Paste")
			(net "P3E_CPU0_PE1_PCH_CON_RXP<12>")
		)
		(pad "79" smd rect
			(at 0 34.403792 270)
			(size 1.1938 0.508)
			(layers "F.Cu" "F.Mask" "F.Paste")
			(net "P3E_CPU0_PE1_PCH_CON_TXN<11>")
		)
		(pad "80" smd rect
			(at 3.4036 34.403792 270)
			(size 1.1938 0.508)
			(layers "F.Cu" "F.Mask" "F.Paste")
			(net "GND")
		)
		(pad "81" smd rect
			(at 0 35.203892 270)
			(size 1.1938 0.508)
			(layers "F.Cu" "F.Mask" "F.Paste")
			(net "P3E_CPU0_PE1_PCH_CON_TXP<11>")
		)
		(pad "82" smd rect
			(at 3.4036 35.203892 270)
			(size 1.1938 0.508)
			(layers "F.Cu" "F.Mask" "F.Paste")
			(net "P3E_CPU0_PE1_PCH_CON_RXN<11>")
		)
		(pad "83" smd rect
			(at 0 36.003992 270)
			(size 1.1938 0.508)
			(layers "F.Cu" "F.Mask" "F.Paste")
			(net "GND")
		)
		(pad "84" smd rect
			(at 3.4036 36.003992 270)
			(size 1.1938 0.508)
			(layers "F.Cu" "F.Mask" "F.Paste")
			(net "P3E_CPU0_PE1_PCH_CON_RXP<11>")
		)
		(pad "85" smd rect
			(at 0 36.804092 270)
			(size 1.1938 0.508)
			(layers "F.Cu" "F.Mask" "F.Paste")
			(net "P3E_CPU0_PE1_PCH_CON_TXN<10>")
		)
		(pad "86" smd rect
			(at 3.4036 36.804092 270)
			(size 1.1938 0.508)
			(layers "F.Cu" "F.Mask" "F.Paste")
			(net "GND")
		)
		(pad "87" smd rect
			(at 0 37.604192 270)
			(size 1.1938 0.508)
			(layers "F.Cu" "F.Mask" "F.Paste")
			(net "P3E_CPU0_PE1_PCH_CON_TXP<10>")
		)
		(pad "88" smd rect
			(at 3.4036 37.604192 270)
			(size 1.1938 0.508)
			(layers "F.Cu" "F.Mask" "F.Paste")
			(net "P3E_CPU0_PE1_PCH_CON_RXN<10>")
		)
		(pad "89" smd rect
			(at 0 38.404292 270)
			(size 1.1938 0.508)
			(layers "F.Cu" "F.Mask" "F.Paste")
			(net "GND")
		)
		(pad "90" smd rect
			(at 3.4036 38.404292 270)
			(size 1.1938 0.508)
			(layers "F.Cu" "F.Mask" "F.Paste")
			(net "P3E_CPU0_PE1_PCH_CON_RXP<10>")
		)
		(pad "91" smd rect
			(at 0 39.204392 270)
			(size 1.1938 0.508)
			(layers "F.Cu" "F.Mask" "F.Paste")
			(net "P3E_CPU0_PE1_PCH_CON_TXN<9>")
		)
	)
)
